(kicad_pcb
	(version 20260206)
	(generator "pcbnew")
	(generator_version "10.0")
	(general
		(thickness 1.6)
		(legacy_teardrops no)
	)
	(paper "A4")
	(title_block
		(title "01162023_DA0F0TEBIF0_F0T_Expander_BD_F_brd_V02_OCP.brd")
		(comment 1 "Grand Teton / footprints 858-863 of 9728")
	)
	(layers
		(0 "F.Cu" signal "TOP")
		(4 "In1.Cu" signal "GND")
		(6 "In2.Cu" signal "VCC")
		(8 "In3.Cu" signal "VCC1")
		(10 "In4.Cu" signal "GND1")
		(12 "In5.Cu" signal "IN1")
		(14 "In6.Cu" signal "GND2")
		(16 "In7.Cu" signal "IN2")
		(18 "In8.Cu" signal "GND3")
		(20 "In9.Cu" signal "IN3")
		(22 "In10.Cu" signal "GND4")
		(24 "In11.Cu" signal "IN4")
		(26 "In12.Cu" signal "GND5")
		(28 "In13.Cu" signal "IN5")
		(30 "In14.Cu" signal "GND6")
		(32 "In15.Cu" signal "IN6")
		(34 "In16.Cu" signal "GND7")
		(2 "B.Cu" signal "BOTTOM")
		(9 "F.Adhes" user "F.Adhesive")
		(11 "B.Adhes" user "B.Adhesive")
		(13 "F.Paste" user "Package Geometry/Pastemask Top")
		(15 "B.Paste" user "Package Geometry/Pastemask Bottom")
		(5 "F.SilkS" user "Ref Des/Silkscreen Top")
		(7 "B.SilkS" user "Ref Des/Silkscreen Bottom")
		(1 "F.Mask" user "Board Geometry/Soldermask Top")
		(3 "B.Mask" user "Board Geometry/Soldermask Bottom")
		(17 "Dwgs.User" user "User.Drawings")
		(19 "Cmts.User" user "User.Comments")
		(21 "Eco1.User" user "User.Eco1")
		(23 "Eco2.User" user "User.Eco2")
		(25 "Edge.Cuts" user "Board Geometry/Outline")
		(27 "Margin" user)
		(31 "F.CrtYd" user "Package Geometry/Place Bound Top")
		(29 "B.CrtYd" user "Package Geometry/Place Bound Bottom")
		(35 "F.Fab" user "Ref Des/Assembly Top")
		(33 "B.Fab" user "Ref Des/Assembly Bottom")
	)
	(footprint ""
		(layer "F.Cu")
		(at 325.265542 -304.036476 90)
		(property "Reference" "R4182"
			(at 0 0 90)
			(layer "F.SilkS")
			(hide yes)
			(effects
				(font
					(size 1.27 1.27)
				)
			)
		)
		(property "Value" ""
			(at 0 0 90)
			(layer "F.Fab")
			(effects
				(font
					(size 1.27 1.27)
				)
			)
		)
		(duplicate_pad_numbers_are_jumpers no)
		(fp_line
			(start 0.7874 -0.4064)
			(end 0.7874 0.4064)
			(stroke
				(width 0.1524)
				(type default)
			)
			(layer "F.SilkS")
		)
		(fp_line
			(start -0.7874 -0.4064)
			(end 0.7874 -0.4064)
			(stroke
				(width 0.1524)
				(type default)
			)
			(layer "F.SilkS")
		)
		(fp_line
			(start 0.7874 0.4064)
			(end -0.7874 0.4064)
			(stroke
				(width 0.1524)
				(type default)
			)
			(layer "F.SilkS")
		)
		(fp_line
			(start -0.7874 0.4064)
			(end -0.7874 -0.4064)
			(stroke
				(width 0.1524)
				(type default)
			)
			(layer "F.SilkS")
		)
		(fp_line
			(start -0.12065 -0.305054)
			(end -0.12065 -0.2794)
			(stroke
				(width 0.1)
				(type default)
			)
			(layer "F.Fab")
		)
		(fp_line
			(start -0.67945 -0.305054)
			(end -0.12065 -0.305054)
			(stroke
				(width 0.1)
				(type default)
			)
			(layer "F.Fab")
		)
		(fp_line
			(start 0.67945 -0.3048)
			(end 0.67945 0.3048)
			(stroke
				(width 0.1)
				(type default)
			)
			(layer "F.Fab")
		)
		(fp_line
			(start 0.12065 -0.3048)
			(end 0.67945 -0.3048)
			(stroke
				(width 0.1)
				(type default)
			)
			(layer "F.Fab")
		)
		(fp_line
			(start 0.12065 -0.2794)
			(end 0.12065 -0.3048)
			(stroke
				(width 0.1)
				(type default)
			)
			(layer "F.Fab")
		)
		(fp_line
			(start -0.12065 -0.2794)
			(end 0.12065 -0.2794)
			(stroke
				(width 0.1)
				(type default)
			)
			(layer "F.Fab")
		)
		(fp_line
			(start 0.120396 0.2794)
			(end -0.12065 0.2794)
			(stroke
				(width 0.1)
				(type default)
			)
			(layer "F.Fab")
		)
		(fp_line
			(start -0.12065 0.2794)
			(end -0.12065 0.3048)
			(stroke
				(width 0.1)
				(type default)
			)
			(layer "F.Fab")
		)
		(fp_line
			(start 0.67945 0.3048)
			(end 0.120396 0.3048)
			(stroke
				(width 0.1)
				(type default)
			)
			(layer "F.Fab")
		)
		(fp_line
			(start 0.120396 0.3048)
			(end 0.120396 0.2794)
			(stroke
				(width 0.1)
				(type default)
			)
			(layer "F.Fab")
		)
		(fp_line
			(start -0.12065 0.3048)
			(end -0.67945 0.3048)
			(stroke
				(width 0.1)
				(type default)
			)
			(layer "F.Fab")
		)
		(fp_line
			(start -0.67945 0.3048)
			(end -0.67945 -0.305054)
			(stroke
				(width 0.1)
				(type default)
			)
			(layer "F.Fab")
		)
		(pad "1" smd circle
			(at -0.40005 0 90)
			(size 0 0)
			(layers "F.Cu" "F.Mask" "F.Paste")
			(net "GND")
		)
		(pad "2" smd circle
			(at 0.40005 0 90)
			(size 0 0)
			(layers "F.Cu" "F.Mask" "F.Paste")
			(net "PEX2_EXT_GPIO_LATCH_N")
		)
	)
	(footprint ""
		(layer "F.Cu")
		(at 111.313976 -271.703546 -90)
		(property "Reference" "PC64"
			(at 0 0 270)
			(layer "F.SilkS")
			(hide yes)
			(effects
				(font
					(size 1.27 1.27)
				)
			)
		)
		(property "Value" ""
			(at 0 0 270)
			(layer "F.Fab")
			(effects
				(font
					(size 1.27 1.27)
				)
			)
		)
		(duplicate_pad_numbers_are_jumpers no)
		(fp_line
			(start -2.146046 3.400044)
			(end -3.400044 2.146046)
			(stroke
				(width 0.1524)
				(type default)
			)
			(layer "F.SilkS")
		)
		(fp_line
			(start 3.400044 3.400044)
			(end -2.146046 3.400044)
			(stroke
				(width 0.1524)
				(type default)
			)
			(layer "F.SilkS")
		)
		(fp_line
			(start -3.400044 2.146046)
			(end -3.400044 0.9398)
			(stroke
				(width 0.1524)
				(type default)
			)
			(layer "F.SilkS")
		)
		(fp_line
			(start 3.400044 0.9398)
			(end 3.400044 3.400044)
			(stroke
				(width 0.1524)
				(type default)
			)
			(layer "F.SilkS")
		)
		(fp_line
			(start 3.400044 -0.9398)
			(end 3.400044 -3.400044)
			(stroke
				(width 0.1524)
				(type default)
			)
			(layer "F.SilkS")
		)
		(fp_line
			(start -3.400044 -2.146046)
			(end -3.400044 -0.9398)
			(stroke
				(width 0.1524)
				(type default)
			)
			(layer "F.SilkS")
		)
		(fp_line
			(start -2.146046 -3.400044)
			(end -3.400044 -2.146046)
			(stroke
				(width 0.1524)
				(type default)
			)
			(layer "F.SilkS")
		)
		(fp_line
			(start 3.400044 -3.400044)
			(end -2.146046 -3.400044)
			(stroke
				(width 0.1524)
				(type default)
			)
			(layer "F.SilkS")
		)
		(fp_line
			(start -3.400044 3.400044)
			(end 3.400044 3.400044)
			(stroke
				(width 0.1)
				(type default)
			)
			(layer "F.Fab")
		)
		(fp_line
			(start 3.400044 3.400044)
			(end 3.400044 -3.400044)
			(stroke
				(width 0.1)
				(type default)
			)
			(layer "F.Fab")
		)
		(fp_line
			(start -3.400044 -3.400044)
			(end -3.400044 3.400044)
			(stroke
				(width 0.1)
				(type default)
			)
			(layer "F.Fab")
		)
		(fp_line
			(start 3.400044 -3.400044)
			(end -3.400044 -3.400044)
			(stroke
				(width 0.1)
				(type default)
			)
			(layer "F.Fab")
		)
		(pad "1" smd rect
			(at -2.70002 0 180)
			(size 1.6002 3.5052)
			(layers "F.Cu" "F.Mask" "F.Paste")
			(net "SW_P12V_P0V8_PEX0_FLT")
		)
		(pad "2" smd rect
			(at 2.70002 0 180)
			(size 1.6002 3.5052)
			(layers "F.Cu" "F.Mask" "F.Paste")
			(net "GND")
		)
	)
	(footprint ""
		(layer "F.Cu")
		(at 392.226546 -25.432004 -90)
		(property "Reference" "C978"
			(at 0 0 270)
			(layer "F.SilkS")
			(hide yes)
			(effects
				(font
					(size 1.27 1.27)
				)
			)
		)
		(property "Value" ""
			(at 0 0 270)
			(layer "F.Fab")
			(effects
				(font
					(size 1.27 1.27)
				)
			)
		)
		(duplicate_pad_numbers_are_jumpers no)
		(fp_line
			(start -0.7874 0.4064)
			(end -0.7874 -0.4064)
			(stroke
				(width 0.1524)
				(type default)
			)
			(layer "F.SilkS")
		)
		(fp_line
			(start 0.7874 0.4064)
			(end -0.7874 0.4064)
			(stroke
				(width 0.1524)
				(type default)
			)
			(layer "F.SilkS")
		)
		(fp_line
			(start -0.7874 -0.4064)
			(end 0.7874 -0.4064)
			(stroke
				(width 0.1524)
				(type default)
			)
			(layer "F.SilkS")
		)
		(fp_line
			(start 0.7874 -0.4064)
			(end 0.7874 0.4064)
			(stroke
				(width 0.1524)
				(type default)
			)
			(layer "F.SilkS")
		)
		(fp_line
			(start -0.67945 0.3048)
			(end -0.67945 -0.305054)
			(stroke
				(width 0.1)
				(type default)
			)
			(layer "F.Fab")
		)
		(fp_line
			(start -0.12065 0.3048)
			(end -0.67945 0.3048)
			(stroke
				(width 0.1)
				(type default)
			)
			(layer "F.Fab")
		)
		(fp_line
			(start 0.120396 0.3048)
			(end 0.120396 0.2794)
			(stroke
				(width 0.1)
				(type default)
			)
			(layer "F.Fab")
		)
		(fp_line
			(start 0.67945 0.3048)
			(end 0.120396 0.3048)
			(stroke
				(width 0.1)
				(type default)
			)
			(layer "F.Fab")
		)
		(fp_line
			(start -0.12065 0.2794)
			(end -0.12065 0.3048)
			(stroke
				(width 0.1)
				(type default)
			)
			(layer "F.Fab")
		)
		(fp_line
			(start 0.120396 0.2794)
			(end -0.12065 0.2794)
			(stroke
				(width 0.1)
				(type default)
			)
			(layer "F.Fab")
		)
		(fp_line
			(start -0.12065 -0.2794)
			(end 0.12065 -0.2794)
			(stroke
				(width 0.1)
				(type default)
			)
			(layer "F.Fab")
		)
		(fp_line
			(start 0.12065 -0.2794)
			(end 0.12065 -0.3048)
			(stroke
				(width 0.1)
				(type default)
			)
			(layer "F.Fab")
		)
		(fp_line
			(start 0.12065 -0.3048)
			(end 0.67945 -0.3048)
			(stroke
				(width 0.1)
				(type default)
			)
			(layer "F.Fab")
		)
		(fp_line
			(start 0.67945 -0.3048)
			(end 0.67945 0.3048)
			(stroke
				(width 0.1)
				(type default)
			)
			(layer "F.Fab")
		)
		(fp_line
			(start -0.67945 -0.305054)
			(end -0.12065 -0.305054)
			(stroke
				(width 0.1)
				(type default)
			)
			(layer "F.Fab")
		)
		(fp_line
			(start -0.12065 -0.305054)
			(end -0.12065 -0.2794)
			(stroke
				(width 0.1)
				(type default)
			)
			(layer "F.Fab")
		)
		(pad "1" smd circle
			(at -0.40005 0 270)
			(size 0 0)
			(layers "F.Cu" "F.Mask" "F.Paste")
			(net "GND")
		)
		(pad "2" smd circle
			(at 0.40005 0 270)
			(size 0 0)
			(layers "F.Cu" "F.Mask" "F.Paste")
			(net "P3V3_SSD13")
		)
	)
	(footprint ""
		(layer "F.Cu")
		(at 380.770384 -250.070874 -90)
		(property "Reference" "R1413"
			(at 0 0 270)
			(layer "F.SilkS")
			(hide yes)
			(effects
				(font
					(size 1.27 1.27)
				)
			)
		)
		(property "Value" ""
			(at 0 0 270)
			(layer "F.Fab")
			(effects
				(font
					(size 1.27 1.27)
				)
			)
		)
		(duplicate_pad_numbers_are_jumpers no)
		(fp_line
			(start -0.7874 0.4064)
			(end -0.7874 -0.4064)
			(stroke
				(width 0.1524)
				(type default)
			)
			(layer "F.SilkS")
		)
		(fp_line
			(start 0.7874 0.4064)
			(end -0.7874 0.4064)
			(stroke
				(width 0.1524)
				(type default)
			)
			(layer "F.SilkS")
		)
		(fp_line
			(start -0.7874 -0.4064)
			(end 0.7874 -0.4064)
			(stroke
				(width 0.1524)
				(type default)
			)
			(layer "F.SilkS")
		)
		(fp_line
			(start 0.7874 -0.4064)
			(end 0.7874 0.4064)
			(stroke
				(width 0.1524)
				(type default)
			)
			(layer "F.SilkS")
		)
		(fp_line
			(start -0.67945 0.3048)
			(end -0.67945 -0.305054)
			(stroke
				(width 0.1)
				(type default)
			)
			(layer "F.Fab")
		)
		(fp_line
			(start -0.12065 0.3048)
			(end -0.67945 0.3048)
			(stroke
				(width 0.1)
				(type default)
			)
			(layer "F.Fab")
		)
		(fp_line
			(start 0.120396 0.3048)
			(end 0.120396 0.2794)
			(stroke
				(width 0.1)
				(type default)
			)
			(layer "F.Fab")
		)
		(fp_line
			(start 0.67945 0.3048)
			(end 0.120396 0.3048)
			(stroke
				(width 0.1)
				(type default)
			)
			(layer "F.Fab")
		)
		(fp_line
			(start -0.12065 0.2794)
			(end -0.12065 0.3048)
			(stroke
				(width 0.1)
				(type default)
			)
			(layer "F.Fab")
		)
		(fp_line
			(start 0.120396 0.2794)
			(end -0.12065 0.2794)
			(stroke
				(width 0.1)
				(type default)
			)
			(layer "F.Fab")
		)
		(fp_line
			(start -0.12065 -0.2794)
			(end 0.12065 -0.2794)
			(stroke
				(width 0.1)
				(type default)
			)
			(layer "F.Fab")
		)
		(fp_line
			(start 0.12065 -0.2794)
			(end 0.12065 -0.3048)
			(stroke
				(width 0.1)
				(type default)
			)
			(layer "F.Fab")
		)
		(fp_line
			(start 0.12065 -0.3048)
			(end 0.67945 -0.3048)
			(stroke
				(width 0.1)
				(type default)
			)
			(layer "F.Fab")
		)
		(fp_line
			(start 0.67945 -0.3048)
			(end 0.67945 0.3048)
			(stroke
				(width 0.1)
				(type default)
			)
			(layer "F.Fab")
		)
		(fp_line
			(start -0.67945 -0.305054)
			(end -0.12065 -0.305054)
			(stroke
				(width 0.1)
				(type default)
			)
			(layer "F.Fab")
		)
		(fp_line
			(start -0.12065 -0.305054)
			(end -0.12065 -0.2794)
			(stroke
				(width 0.1)
				(type default)
			)
			(layer "F.Fab")
		)
		(pad "1" smd circle
			(at -0.40005 0 270)
			(size 0 0)
			(layers "F.Cu" "F.Mask" "F.Paste")
			(net "PEX3_MODE_SEL8")
		)
		(pad "2" smd circle
			(at 0.40005 0 270)
			(size 0 0)
			(layers "F.Cu" "F.Mask" "F.Paste")
			(net "P1V8_PEX")
		)
	)
	(footprint ""
		(layer "F.Cu")
		(at 375.512838 -9.713976 180)
		(property "Reference" "C3871"
			(at 0 0 180)
			(layer "F.SilkS")
			(hide yes)
			(effects
				(font
					(size 1.27 1.27)
				)
			)
		)
		(property "Value" ""
			(at 0 0 180)
			(layer "F.Fab")
			(effects
				(font
					(size 1.27 1.27)
				)
			)
		)
		(duplicate_pad_numbers_are_jumpers no)
		(fp_line
			(start 0.7874 0.4064)
			(end -0.7874 0.4064)
			(stroke
				(width 0.1524)
				(type default)
			)
			(layer "F.SilkS")
		)
		(fp_line
			(start 0.7874 -0.4064)
			(end 0.7874 0.4064)
			(stroke
				(width 0.1524)
				(type default)
			)
			(layer "F.SilkS")
		)
		(fp_line
			(start -0.7874 0.4064)
			(end -0.7874 -0.4064)
			(stroke
				(width 0.1524)
				(type default)
			)
			(layer "F.SilkS")
		)
		(fp_line
			(start -0.7874 -0.4064)
			(end 0.7874 -0.4064)
			(stroke
				(width 0.1524)
				(type default)
			)
			(layer "F.SilkS")
		)
		(fp_line
			(start 0.67945 0.3048)
			(end 0.120396 0.3048)
			(stroke
				(width 0.1)
				(type default)
			)
			(layer "F.Fab")
		)
		(fp_line
			(start 0.67945 -0.3048)
			(end 0.67945 0.3048)
			(stroke
				(width 0.1)
				(type default)
			)
			(layer "F.Fab")
		)
		(fp_line
			(start 0.12065 -0.2794)
			(end 0.12065 -0.3048)
			(stroke
				(width 0.1)
				(type default)
			)
			(layer "F.Fab")
		)
		(fp_line
			(start 0.12065 -0.3048)
			(end 0.67945 -0.3048)
			(stroke
				(width 0.1)
				(type default)
			)
			(layer "F.Fab")
		)
		(fp_line
			(start 0.120396 0.3048)
			(end 0.120396 0.2794)
			(stroke
				(width 0.1)
				(type default)
			)
			(layer "F.Fab")
		)
		(fp_line
			(start 0.120396 0.2794)
			(end -0.12065 0.2794)
			(stroke
				(width 0.1)
				(type default)
			)
			(layer "F.Fab")
		)
		(fp_line
			(start -0.12065 0.3048)
			(end -0.67945 0.3048)
			(stroke
				(width 0.1)
				(type default)
			)
			(layer "F.Fab")
		)
		(fp_line
			(start -0.12065 0.2794)
			(end -0.12065 0.3048)
			(stroke
				(width 0.1)
				(type default)
			)
			(layer "F.Fab")
		)
		(fp_line
			(start -0.12065 -0.2794)
			(end 0.12065 -0.2794)
			(stroke
				(width 0.1)
				(type default)
			)
			(layer "F.Fab")
		)
		(fp_line
			(start -0.12065 -0.305054)
			(end -0.12065 -0.2794)
			(stroke
				(width 0.1)
				(type default)
			)
			(layer "F.Fab")
		)
		(fp_line
			(start -0.67945 0.3048)
			(end -0.67945 -0.305054)
			(stroke
				(width 0.1)
				(type default)
			)
			(layer "F.Fab")
		)
		(fp_line
			(start -0.67945 -0.305054)
			(end -0.12065 -0.305054)
			(stroke
				(width 0.1)
				(type default)
			)
			(layer "F.Fab")
		)
		(pad "1" smd circle
			(at -0.40005 0 180)
			(size 0 0)
			(layers "F.Cu" "F.Mask" "F.Paste")
			(net "P3V3_AUX")
		)
		(pad "2" smd circle
			(at 0.40005 0 180)
			(size 0 0)
			(layers "F.Cu" "F.Mask" "F.Paste")
			(net "GND")
		)
	)
	(footprint ""
		(layer "F.Cu")
		(at 405.88946 -63.56223)
		(property "Reference" "Q210"
			(at 0.00254 -1.8669 0)
			(unlocked yes)
			(layer "F.SilkS")
			(effects
				(font
					(size 0.7874 0.5842)
					(thickness 0.1524)
				)
			)
		)
		(property "Value" ""
			(at 0 0 0)
			(layer "F.Fab")
			(effects
				(font
					(size 1.27 1.27)
				)
			)
		)
		(duplicate_pad_numbers_are_jumpers no)
		(fp_line
			(start -1.376172 -1.199896)
			(end -0.508 -1.199896)
			(stroke
				(width 0.1524)
				(type default)
			)
			(layer "F.SilkS")
		)
		(fp_line
			(start -1.376172 1.199896)
			(end -1.376172 -1.199896)
			(stroke
				(width 0.1524)
				(type default)
			)
			(layer "F.SilkS")
		)
		(fp_line
			(start -0.508 -1.199896)
			(end 0 -0.762)
			(stroke
				(width 0.1524)
				(type default)
			)
			(layer "F.SilkS")
		)
		(fp_line
			(start 0 -0.762)
			(end 0.508 -1.199896)
			(stroke
				(width 0.1524)
				(type default)
			)
			(layer "F.SilkS")
		)
		(fp_line
			(start 0.508 -1.199896)
			(end 1.376172 -1.199896)
			(stroke
				(width 0.1524)
				(type default)
			)
			(layer "F.SilkS")
		)
		(fp_line
			(start 1.376172 -1.199896)
			(end 1.376172 1.199896)
			(stroke
				(width 0.1524)
				(type default)
			)
			(layer "F.SilkS")
		)
		(fp_line
			(start 1.376172 1.199896)
			(end -1.376172 1.199896)
			(stroke
				(width 0.1524)
				(type default)
			)
			(layer "F.SilkS")
		)
		(fp_poly
			(pts
				(xy -1.478788 -0.890778) (xy -1.748028 -1.699006) (xy -2.287016 -1.160272)
			)
			(stroke
				(width 0)
				(type default)
			)
			(fill yes)
			(layer "F.SilkS")
		)
		(fp_line
			(start -0.674878 -1.100074)
			(end 0.674878 -1.100074)
			(stroke
				(width 0.1)
				(type default)
			)
			(layer "F.Fab")
		)
		(fp_line
			(start -0.674878 1.100074)
			(end -0.674878 -1.100074)
			(stroke
				(width 0.1)
				(type default)
			)
			(layer "F.Fab")
		)
		(fp_line
			(start 0.674878 -1.100074)
			(end 0.674878 1.100074)
			(stroke
				(width 0.1)
				(type default)
			)
			(layer "F.Fab")
		)
		(fp_line
			(start 0.674878 1.100074)
			(end -0.674878 1.100074)
			(stroke
				(width 0.1)
				(type default)
			)
			(layer "F.Fab")
		)
		(fp_poly
			(pts
				(xy -1.4605 -0.7493) (xy -2.2225 -1.1303) (xy -2.2225 -0.3683)
			)
			(stroke
				(width 0)
				(type default)
			)
			(fill yes)
			(layer "F.Fab")
		)
		(pad "1" smd rect
			(at -0.899922 -0.750062 270)
			(size 0.6096 0.6096)
			(layers "F.Cu" "F.Mask" "F.Paste")
			(net "GND")
		)
		(pad "2" smd rect
			(at -0.899922 0 270)
			(size 0.4064 0.6096)
			(layers "F.Cu" "F.Mask" "F.Paste")
			(net "P12V_SSD14_PG_G1")
		)
		(pad "3" smd rect
			(at -0.899922 0.750062 270)
			(size 0.6096 0.6096)
			(layers "F.Cu" "F.Mask" "F.Paste")
			(net "PWRGD_P12V_SSD14_D")
		)
		(pad "4" smd rect
			(at 0.899922 0.750062 270)
			(size 0.6096 0.6096)
			(layers "F.Cu" "F.Mask" "F.Paste")
			(net "GND")
		)
		(pad "5" smd rect
			(at 0.899922 0 270)
			(size 0.4064 0.6096)
			(layers "F.Cu" "F.Mask" "F.Paste")
			(net "P12V_SSD14_PG_G2")
		)
		(pad "6" smd rect
			(at 0.899922 -0.750062 270)
			(size 0.6096 0.6096)
			(layers "F.Cu" "F.Mask" "F.Paste")
			(net "P12V_SSD14_PG_G2")
		)
	)
)
